# Primary and Alternate BOM of B91.01110.0015_FDPB.xls — Sheet0 (bom)
| Part Number | B91.01110.0015 |  |  |  |  |  |  |  |  |  |  |  |  |
| Revision | F |  |  |  |  |  |  |  |  |  |  |  |  |
| Sequence | 1 |  |  |  |  |  |  |  |  |  |  |  |  |
| Description | BRYCE CANYON FRONT DPB GCE-1 P MAIN |  |  |  |  |  |  |  |  |  |  |  |  |
| Project Code | BPD011010001 |  |  |  |  |  |  |  |  |  |  |  |  |
| Latest Revision? | YES |  |  |  |  |  |  |  |  |  |  |  |  |
| PDM BOM List |  |  |  |  |  |  |  |  |  |  |  |  |  |
| Level | Parent Number | Part Number | Description | Green Factor | Manufacturer | Manufacturer Part Number | Source | BOM Usage | M/P Code | S/D | Qty | UoM | Location |
| 1 | B91.01110.0015 | B55.01103.0002 | BRYCE CANYON FRONT DPB GCE-1 P MAIN(D) | R2; |  |  |  | M | Manufacture |  | 1 | PCS |  |
| 2 | B55.01103.0002 | 020.50215.0164 | CONN EDGE 164P G630HAA25062HR | R2_SA;HF_SA; | AMPHENOL | G630HAA25062HR | Single |  | Purchase | DIP | 4 | PCS | MONO1 MONO2 MONO3 MONO4 |
| 2 | B55.01103.0002 | 020.80417.0001 | CONN CTR XCEDE 968-3200-A1H, LCP | R2_SA;HF_SA; | AMPHENOL | 968-3200-A1H | Single |  | Purchase | DIP | 1 | PCS | PWR1 |
| 2 | B55.01103.0002 | 020.80656.0001 | CONN PWR XCEDE JX410-50728 | R2_SA;HF_SA; | AMPHENOL | JX410-50728 | Single |  | Purchase | DIP | 1 | PCS | DPB2 |
| 2 | B55.01103.0002 | 020.80946.0001 | CONN XCEDE JX924-3405-505_REVA | R2_SA;HF_SA; | AMPHENOL | C-924-3405-505_RevA | Single |  | Purchase | DIP | 1 | PCS |  |
| 2 | B55.01103.0002 | 020.80956.0001 | CONN SIGNAL XCEDE 923-3L0E-40H,LCP | R2_SA;HF_SA; | AMPHENOL | 923-3L0E-40H | Single |  | Purchase | DIP | 1 | PCS |  |
| 2 | B55.01103.0002 | 020.80957.0001 | CONN SIGNAL XCEDE 923-300C-40H,LCP | R2_SA;HF_SA; | AMPHENOL | 923-300C-40H | Single |  | Purchase | DIP | 1 | PCS |  |
| 2 | B55.01103.0002 | 020.80958.0001 | CONN SIGNAL XCEDE  923-300E-40H,LCP | R2_SA;HF_SA; | AMPHENOL | 923-300E-40H | Single |  | Purchase | DIP | 2 | PCS |  |
| 2 | B55.01103.0002 | 020.80959.0001 | CON SIGNAL XCEDE JX412-50282_REVA | R2_SA; | AMPHENOL | JX412-50282_RevA | Single |  | Purchase | DIP | 1 | PCS | DPB1 |
| 2 | B55.01103.0002 | 020.80960.0001 | CONN SIGNAL XCEDE JX430-50035_REVB | R2_SA; | AMPHENOL | JX430-50035_RevB | Single |  | Purchase | DIP | 2 | PCS | IO1 IO2 |
| 2 | B55.01103.0002 | 020.80961.0001 | CONN SIGNAL XCEDE 923-310E-30H | R2_SA;HF_SA; | AMPHENOL | 923-310E-30H | Single |  | Purchase | DIP | 1 | PCS | PCIE1 |
| 2 | B55.01103.0002 | 038.0107I.0001 | HOT GLUE DPB BRCA | R2_C; | WISTRON | 038.0107I.0001 | Single |  | Purchase | DIP | 0.001700 | PCS |  |
| 2 | B55.01103.0002 | 086.000BF.0G20 | SCRW #2-56_L3_8_INCH 577-0014-000 | R2_SA;HF_SA; | AMPHENOL | 086.000BF.0G20 | Single |  | Purchase | DIP | 1 | PCS |  |
| 2 | B55.01103.0002 | 086.000LQ.0543 | THUMB SCREW PRESSFIT M3 L3 BC | R2_SA;HF_SA; | FIVETECH | 27-141-201-5 | Single |  | Purchase | DIP | 2 | PCS |  |
| 2 | B55.01103.0002 | 40.58D03.001 | LBL POLYIMIDE31.8*6.35 BARCODE | R2_SA;HF_SA;G_SA; | LABELJET | 40.58D03.001 | Single |  | Purchase | DIP | 2 | PCS |  |
| 2 | B55.01103.0002 | 40.6E727.001 | LBL 50X15MM BLANK WHITE POLYESTER | R2_SA;HF_SA; | WISTRON | 40.6E727.001 | Single |  | Purchase | DIP | 1 | PCS |  |
| 2 | B55.01103.0002 | 640.00X01.0001 | LBL 7X7MM  FOR SONIC | R2_SA;HF_SA; | WISTRON | 640.00X01.0001 | Single |  | Purchase | DIP | 1 | PCS |  |
| 2 | B55.01103.0002 | B42.01101.0001 | GUIDE PIN 914-3000-00A | R2_SA;HF_SA; | AMPHENOL | B42.01101.0001 | Single |  | Purchase | DIP | 1 | PCS |  |
| 2 | B55.01103.0002 | B42.0111I.1001 | CVR XCEDE PWR JX410-50728 MP | R2_SA;HF_SA; | KANGYANG | COVER-18 | Multiple |  | Purchase | DIP | 1 | PCS |  |
| A(Alternative to previous component) | B55.01103.0002 | B42.0111I.0001 | CVR XCEDE PWR JX410-50728 | R2_SA;HF_SA; | KANGYANG | COVER-18 |  |  | Purchase |  |  |  |  |
| 2 | B55.01103.0002 | B42.0111M.1001 | CVR XCEDE SIGNAL JX412-50282 MP | R2_SA;HF_SA; | KANGYANG | COVER-19 | Multiple |  | Purchase | DIP | 1 | PCS |  |
| A | B55.01103.0002 | B42.0111M.0001 | CVR XCEDE SIGNAL JX412-50282 | R2_SA;HF_SA; | KANGYANG | COVER-19 |  |  | Purchase |  |  |  |  |
| 2 | B55.01103.0002 | B42.0111N.1001 | CVR XCEDE SIGNAL JX430-50035 MP | R2_SA;HF_SA; | KANGYANG | COVER-20 | Multiple |  | Purchase | DIP | 2 | PCS |  |
| A | B55.01103.0002 | B42.0111N.0001 | CVR XCEDE SIGNAL JX430-50035 | R2_SA;HF_SA; | KANGYANG | COVER-20 |  |  | Purchase |  |  |  |  |
| 2 | B55.01103.0002 | B55.01103.M002 | BRYCE CANYON FRONT DPB GCE-1 P MAIN(S) | R2; |  |  |  | M | Manufacture | DIP | 1 | PCS |  |
| 3 | B55.01103.M002 | 020.F0496.0040 | CONN WTB 40P G846A40120T1HR SMD | R2_SA;HF_SA; | AMPHENOL | G846A40120T1HR | Single |  | Purchase | SMT | 1 | PCS | LED1 |
| 3 | B55.01103.M002 | 062.10010.0121 | SKT SAS S14+P15 10125550-001C-TRLF ,LCP | R2_SA;HF_SA; | FCI | 10125550-001C-TRLF | Multiple |  | Purchase | SMT | 37 | PCS | HDDSAS0 HDDSAS1 HDDSAS10 HDDSAS11 HDDSAS12 HDDSAS13 HDDSAS14 HDDSAS15 HDDSAS16 HDDSAS17 HDDSAS18 HDDSAS19 HDDSAS2 HDDSAS20 HDDSAS21 HDDSAS22 HDDSAS23 HDDSAS24 HDDSAS25 HDDSAS26 HDDSAS27 HDDSAS28 HDDSAS29 HDDSAS3 HDDSAS30 HDDSAS31 HDDSAS32 HDDSAS33 HDDSAS34 HDDSAS35 HDDSAS4 HDDSAS5 HDDSAS6 HDDSAS7 HDDSAS8 HDDSAS9 IO3 |
| A | B55.01103.M002 | 62.10108.111 | SKT SAS S14+P15 SAS-F313-014-1-TR SMD | R2_SA;HF_SA; | AMPHENOL | SAS-F313-014-1-TR |  |  | Purchase |  |  |  |  |
| 3 | B55.01103.M002 | 064.0U305.0C0N | CHIP RES 0.0003 F 3W 4026 | R2_SA;HF_SA; | VISHAY | WSL4026L3000FEA | Single |  | Purchase | SMT | 1 | PCS | R1166 |
| 3 | B55.01103.M002 | 064.51015.06DS | CHIP RES 5.1K F 1/16W 0402 | R2_SA;HF_SA;G_SA; | YAGEO;WALSIN;KOA | RC0402FR-075K1L;WR04X5101FTL;RK73H1ETQTP5101F | Multiple |  | Purchase | SMT | 3 | PCS | R1066 R1100 R1171 |
| 3 | B55.01103.M002 | 064.71525.06DS | CHIP RES 71.5K F 1/16W 0402 | R2_SA;HF_SA;G_SA; | YAGEO;KOA | RC0402FR-0771K5L;RK73H1ETQTP7152F | Multiple |  | Purchase | SMT | 4 | PCS | R1217 R1236 R1256 R1274 |
| 3 | B55.01103.M002 | 071.00128.000W | IC ADC SYS ADC128D818CIMTX/NOPB TSSOP16P | R2_SA;HF_SA; | TI | ADC128D818CIMTX/NOPB | Single |  | Purchase | SMT | 1 | PCS | U3 |
| 3 | B55.01103.M002 | 071.09555.000W | IC I/O EXPANDER TCA9555PWR TSSOP 24P | R2_SA;HF_SA; | TI | TCA9555PWR | Multiple |  | Purchase | SMT | 11 | PCS | U10 U11 U12 U17 U18 U19 U4 U5 U6 U7 U8 |
| A | B55.01103.M002 | 71.09555.B0W | IC IO PCA9555PWRG4 TSSOP 24P | R2_SA;HF_SA; | TI | PCA9555PWRG4 |  |  | Purchase |  |  |  |  |
| 3 | B55.01103.M002 | 074.01278.0A7Z | IC SWAP CTRL ADM1278-2ACPZ-RL LFCSP 32P | R2_SA;HF_SA; | ADI | ADM1278-2ACPZ-RL | Single |  | Purchase | SMT | 3 | PCS | U23 U24 U26 |
| 3 | B55.01103.M002 | 078.10321.02S1 | CHIP CAP C 0.01U 16V K0201 X7R | R2_SA;HF_SA;G_SA; | DARFON;MURATA;TAIYO;WALSIN;YAGEO;SAMSUNG | C0603X7R103KET;GRM033R71C103KE14D;EMK063B7103KP-F;0201B103K160CT;CC0201KRX7R7BB103;CL03B103KO3NNNC | Multiple |  | Purchase | SMT | 72 | PCS | C103 C104 C116 C117 C129 C130 C142 C143 C155 C156 C168 C169 C181 C182 C194 C195 C207 C208 C220 C221 C233 C234 C246 C247 C259 C260 C272 C273 C285 C286 C298 C299 C311 C312 C324 C325 C337 C338 C350 C351 C363 C364 C376 C377 C389 C390 C402 C403 C415 C416 C428 C429 C441 C442 C454 C455 C467 C468 C480 C481 C493 C494 C506 C507 C51 C52 C64 C65 C77 C78 C90 C91 |
| 3 | B55.01103.M002 | 078.10621.0211 | CHIP CAP C 10UF 16V K0805 X7R | R2_SA;HF_SA;G_SA; | SAMSUNG;YAGEO | CL21B106KOQNNNE;CC0805KKX7R7BB106 | Multiple |  | Purchase | SMT | 36 | PCS | C40 C44 C597 C598 C599 C601 C602 C611 C612 C613 C614 C615 C616 C618 C619 C628 C629 C630 C631 C632 C633 C635 C636 C645 C646 C647 C648 C649 C650 C652 C653 C662 C663 C664 C671 C672 |
| 3 | B55.01103.M002 | 078.22622.M001 | CHIP CAP C 22U 25V K1206 X6S(FACEBOOK) | R2_SA;HF_SA; | MURATA | GRM31CC81E226KE11L | Multiple |  | Purchase | SMT | 6 | PCS | C121 C134 C32 C41 C520 C529 |
| A | B55.01103.M002 | 078.22622.0521 | CHIP CAP C 22U 25V K1206 X5R | R2_SA;HF_SA;G_SA; | YAGEO;SAMSUNG;MURATA;WALSIN;DARFON | CC1206KKX5R8BB226;CL31A226KAHNNNE;GRM31CR61E226KE15L;1206X226K250CT;C3216X5R226KFP |  |  | Purchase |  |  |  |  |
| A | B55.01103.M002 | 078.22622.0821 | CHIP CAP C 22U 25V K1206 X6S | R2_SA;HF_SA; | MURATA;WALSIN | GRM31CC81E226KE11L;1206S226K250CT |  |  | Purchase |  |  |  |  |
| A | B55.01103.M002 | 078.22622.082N | CHIP CAP C 22U 25V K1206 X6S | R2_SA;HF_SA; | MURATA | GRM31CC81E226KE11K |  |  | Purchase |  |  |  |  |
| 3 | B55.01103.M002 | 078.47522.0211 | CHIP CAP C 4.7U 25V K0805 X7R | R2_SA;HF_SA;G_SA; | DARFON;MURATA;SAMSUNG;TAIYO;WALSIN;YAGEO | C2012X7R475KFP;GRM21BR71E475KA73L;CL21B475KAFNNNE;TMK212AB7475KG-T;0805B475K250CT;CC0805KKX7R8BB475 | Multiple |  | Purchase | SMT | 36 | PCS | C109 C122 C135 C150 C161 C174 C187 C202 C214 C227 C241 C254 C266 C278 C291 C305 C318 C330 C343 C357 C369 C383 C397 C409 C421 C435 C447 C461 C473 C486 C500 C514 C58 C72 C83 C96 |
| 3 | B55.01103.M002 | 079.2771D.0011 | CHIP CAP 270UF 16V M 6.3*9.9 SVPG OS-CON | R2_SA;HF_SA; | PANASONIC | 16SVPG270M | Single |  | Purchase | SMT | 6 | PCS | TC13 TC14 TC15 TC16 TC17 TC18 |
| 3 | B55.01103.M002 | 083.00195.0B70 | LED B/Y LTST-C195TBJSKTINV SMD | R2_SA;HF_SA; | LITEON | LTST-C195TBJSKTINV | Multiple |  | Purchase | SMT | 36 | PCS | FLED1 FLED10 FLED11 FLED12 FLED13 FLED14 FLED15 FLED16 FLED17 FLED18 FLED19 FLED2 FLED20 FLED21 FLED22 FLED23 FLED24 FLED3 FLED4 FLED5 FLED6 FLED7 FLED8 FLED9 RLED25 RLED26 RLED27 RLED28 RLED29 RLED30 RLED31 RLED32 RLED33 RLED34 RLED35 RLED36 |
| A | B55.01103.M002 | 83.19223.H70 | LED Y/B 19-223/Y2BHC-C01/2TSM | R2_SA;HF_SA; | EVERLIGHT | 19-223/Y2BHC-C01/2T |  |  | Purchase |  |  |  |  |
| 3 | B55.01103.M002 | 084.08201.0037 | FET MOS IRFH8201TRPBF PQFN 5X6 8P | R2_SA;HF_SA; | IR | IRFH8201TRPBF | Multiple |  | Purchase | SMT | 5 | PCS | Q220 Q222 Q226 Q227 Q228 |
| A | B55.01103.M002 | 084.00925.003N | FET MOS PH0925CL,115 NC LFPAK 4P | R2_SA;HF_SA; | NXP | PH0925CL,115 |  |  | Purchase |  |  |  |  |
| 3 | B55.01103.M002 | 084.3K324.0031 | FET MOS NC SSM3K324R SOT-23F 3P | R2_SA;HF_SA; | TOSHIBA | SSM3K324R | Multiple |  | Purchase | SMT | 39 | PCS | Q15 Q16 Q17 Q263 Q264 Q265 Q266 Q267 Q268 Q269 Q270 Q271 Q272 Q273 Q274 Q275 Q276 Q277 Q278 Q279 Q280 Q281 Q282 Q283 Q284 Q285 Q286 Q287 Q288 Q289 Q290 Q291 Q292 Q293 Q294 Q295 Q296 Q297 Q299 |
| A | B55.01103.M002 | 084.06244.0031 | FET MOS IRLML6244TRPBF SOT-23 | R2_SA;HF_SA; | IR | IRLML6244TRPBF |  |  | Purchase |  |  |  |  |
| 3 | B55.01103.M002 | 087.71242.0465 | NUT TPM M3*0.5*L6 NI EVT | R2_SA;HF_SA; | ?? | 087.71242.0465 | Single |  | Purchase | SMT | 8 | PCS | NUT1 NUT2 NUT3 NUT4 NUT5 NUT6 NUT7 NUT8 |
| 3 | B55.01103.M002 | 63.00000.00L | CHIP RES 0 J 1/10W 0603 | R2_SA;HF_SA;G_SA; | TA-I ; RALEC ; YAGEO ; WALSIN | RM06JTN0 ; RTT03000JTP ; RC0603JR-070RL ; WR06X000PTL | Multiple |  | Purchase | SMT | 4 | PCS | R1209 R1228 R1247 R1266 |
| 3 | B55.01103.M002 | 63.33334.1DL | CHIP RES 33K J 1/16W 0402 | R2_SA;HF_SA;G_SA; | TA-I;RALEC;CYNTEC;YAGEO;WALSIN | RM04JTN333;RTT02333JTH;RR0510S-333-JN;RC0402JR-0733KL;WR04X333JTL | Multiple |  | Purchase | SMT | 1 | PCS | R1285 |
| 3 | B55.01103.M002 | 63.47234.1DL | CHIP RES 4.7K J 1/16W 0402 | R2_SA;HF_SA;G_SA; | TA-I;RALEC;CYNTEC;YAGEO;WALSIN | RM04JTN472 ; RTT02472JTH ; RR0510S-472-JN ; RC0402JR-074K7L;WR04X472JTL | Multiple |  | Purchase | SMT | 182 | PCS | R13 R14 R145 R146 R147 R160 R164 R166 R183 R189 R190 R206 R212 R213 R229 R235 R236 R252 R258 R259 R275 R281 R282 R298 R304 R305 R321 R327 R328 R344 R350 R351 R367 R373 R374 R390 R395 R397 R413 R419 R420 R436 R441 R444 R457 R458 R459 R461 R462 R464 R465 R466 R470 R471 R472 R473 R477 R478 R480 R481 R482 R484 R486 R487 R488 R489 R493 R494 R495 R496 R500 R501 R503 R504 R505 R507 R508 R510 R511 R512 R516 R517 R518 R519 R523 R524 R526 R527 R528 R530 R532 R533 R534 R535 R539 R540 R541 R542 R546 R547 R549 R550 R551 R553 R554 R556 R557 R558 R562 R563 R564 R565 R569 R570 R572 R573 R574 R576 R578 R579 R580 R581 R585 R586 R587 R588 R592 R593 R595 R596 R597 R599 R602 R604 R620 R625 R627 R643 R649 R650 R666 R671 R674 R689 R695 R696 R712 R717 R719 R735 R740 R742 R758 R763 R765 R781 R787 R788 R804 R810 R811 R827 R833 R834 R850 R855 R856 R873 R878 R879 R896 R901 R902 R919 R924 R927 R942 R947 R949 R965 R970 R972 |
| 3 | B55.01103.M002 | 63.R0031.16L | CHIP RES 0 J 1/8W 0805 | R2_SA;HF_SA;G_SA; | TAI;RALEC;YAGEO;WALSIN | RM10JTN0 ; RTT05000JTP ; RC0805JR-070RL ; WR08X000PTL | Multiple |  | Purchase | SMT | 6 | PCS | R1069 R1103 R1177 R142 R143 R144 |
| 3 | B55.01103.M002 | 63.R0032.11L | CHIP RES 0 J 1/4W 1206 (ROHS) | R2_SA;HF_SA;G_SA; | TA-I ; RALEC ; YAGEO; WALSIN | RM12JTN0 ; RTT06000JTP ; RC1206JR-070RL; WR12X000 PTL | Multiple |  | Purchase | SMT | 1 | PCS | R1282 |
| 3 | B55.01103.M002 | 63.R0034.1DL | CHIP RES 0 J 1/16W 0402 | R2_SA;HF_SA;G_SA; | TAI;RALEC;CYNTEC;YAGEO;WALSIN | RM04JTN0;RTT02000JTH;RR0510X-000-XN;RC0402JR-070RL;WR04X000PTL | Multiple |  | Purchase | SMT | 153 | PCS | R10 R100 R1010 R1040 R1041 R1042 R1043 R105 R106 R1074 R1075 R1076 R1077 R11 R114 R1142 R1143 R1144 R1145 R115 R12 R1207 R1223 R1225 R123 R1242 R1244 R125 R1261 R1263 R1279 R1286 R1287 R1292 R15 R156 R157 R159 R16 R163 R170 R172 R178 R181 R187 R193 R204 R21 R211 R216 R22 R234 R239 R256 R262 R279 R285 R29 R30 R302 R308 R325 R331 R348 R349 R35 R354 R355 R356 R357 R358 R361 R365 R366 R369 R372 R377 R394 R4 R40 R400 R417 R423 R43 R439 R446 R449 R450 R463 R469 R47 R485 R492 R5 R509 R515 R52 R531 R538 R555 R56 R561 R57 R577 R58 R584 R59 R600 R607 R624 R630 R639 R641 R642 R647 R65 R653 R669 R676 R693 R699 R71 R716 R722 R739 R745 R761 R768 R785 R791 R808 R814 R82 R83 R831 R837 R853 R860 R87 R876 R883 R899 R906 R922 R929 R93 R945 R95 R952 R968 R975 R980 R984 |
| 3 | B55.01103.M002 | 64.10006.6DL | CHIP RES 100 D 1/16W 0402 | R2_SA;HF_SA;G_SA; | RALEC;TAI;CYNTEC;YAGEO | RTT021000DTH;RM04DTN1000;RR0510P-101-DN;RC0402DR-07100RL | Multiple |  | Purchase | SMT | 6 | PCS | R1037 R1038 R1071 R1072 R1139 R1140 |
| 3 | B55.01103.M002 | 64.10015.6DL | CHIP RES 1K F 1/16W 0402 | R2_SA;HF_SA;G_SA; | TA-I;RALEC;CYNTEC;YAGEO;WALSIN | RM04FTN1001 ; RTT021001FTH ; RR0510S-102-FN ; RC0402FR-071KL;WR04X1001FTL | Multiple |  | Purchase | SMT | 15 | PCS | R1068 R1102 R1176 R402 R403 R412 R415 R427 R431 R432 R434 R435 R438 R440 R443 |
| 3 | B55.01103.M002 | 64.10025.6DL | CHIP RES 10K F 1/16W 0402 | R2_SA;HF_SA;G_SA; | TA-I;RALEC;CYNTEC;YAGEO;WALSIN | RM04FTN1002 ; RTT021002FTH ; RR0510S-103-FN ; RC0402FR-0710KL;WR04X1002FTL | Multiple |  | Purchase | SMT | 79 | PCS | R1051 R1085 R1107 R1153 R1210 R1221 R1229 R1241 R1248 R1259 R1267 R1280 R1283 R1288 R130 R131 R153 R162 R168 R177 R185 R19 R20 R201 R224 R245 R270 R291 R314 R337 R360 R371 R381 R383 R385 R386 R388 R389 R392 R393 R396 R401 R406 R409 R411 R424 R429 R452 R475 R498 R521 R544 R567 R590 R610 R611 R613 R615 R616 R632 R633 R634 R636 R638 R659 R682 R705 R728 R751 R774 R797 R820 R843 R866 R889 R9 R912 R935 R958 |
| 3 | B55.01103.M002 | 64.10035.6DL | CHIP RES 100K F 1/16W 0402 | R2_SA;HF_SA;G_SA; | TA-I;RALEC;CYNTEC;YAGEO;WALSIN | RM04FTN1003 ; RTT021003FTH ; RR0510S-104-FN ; RC0402FR-07100KL;WR04X1003FTL | Multiple |  | Purchase | SMT | 35 | PCS | R1001 R1002 R1003 R1004 R1006 R1007 R1008 R1044 R1049 R1050 R1056 R1058 R1060 R1084 R1090 R1092 R1094 R1128 R1129 R1130 R1152 R1160 R1162 R1164 R378 R379 R380 R42 R75 R987 R992 R993 R994 R995 R996 |
| 3 | B55.01103.M002 | 64.10R05.16L | CHIP RES 10 F 1/8W 0805(ROHS) | R2_SA;HF_SA;G_SA; | TAI;YAGEO;RALEC | RM10FTN10R0;RC0805FR-0710RL;RTT0510R0FTP | Multiple |  | Purchase | SMT | 5 | PCS | R1067 R1101 R1172 R1173 R1174 |
| 3 | B55.01103.M002 | 64.10R05.55L | CHIP RES 10 F 1/10W 0603 | R2_SA;HF_SA;G_SA; | TA-I;RALEC;YAGEO;WALSIN | RM06FTN10R0 ; RTT0310R0FTP ; RC0603FR-0710RL;WR06X10R0FTL | Multiple |  | Purchase | SMT | 5 | PCS | R1216 R1235 R1254 R1273 R1284 |
| 3 | B55.01103.M002 | 64.10R05.6DL | CHIP RES 10 F 1/16W 0402 | R2_SA;HF_SA;G_SA; | TAI;RALEC;CYNTEC;YAGEO;WALSIN | RM04FTN10R0;RTT0210R0FTH;RR0510S-100-FN;RC0402FR-0710RL;WR04X10R0FTL | Multiple |  | Purchase | SMT | 15 | PCS | R1039 R1052 R1053 R1073 R1078 R1081 R1086 R1087 R1105 R1106 R1141 R1154 R1155 R1156 R1157 |
| 3 | B55.01103.M002 | 64.11025.6DL | CHIP RES 11K F 1/16W 0402 | R2_SA;HF_SA;G_SA; | TA-I ; RALEC ; CYNTEC ; YAGEO;WALSIN | RM04FTN1102 ; RTT021102FTH ; RR0510S-1102-FN ; RC0402FR-0711KL;WR04X1102FTL | Multiple |  | Purchase | SMT | 3 | PCS | R1054 R1088 R1158 |
| 3 | B55.01103.M002 | 64.12425.6DL | CHIP RES 12.4K F 1/16W 0402 | R2_SA;HF_SA;G_SA; | TA-I;RALEC;CYNTEC;YAGEO | RM04FTN1242;RTT021242FTH;RR0510S-1242-FN;RC0402FR-0712K4L | Multiple |  | Purchase | SMT | 1 | PCS | R1165 |
| 3 | B55.01103.M002 | 64.13005.55L | CHIP RES 130 F 1/10W 0603 | R2_SA;HF_SA;G_SA; | TA-I ; RALEC ; YAGEO | RM06FTN1300 ; RTT031300FTP ; RC0603FR-07130RL | Multiple |  | Purchase | SMT | 36 | PCS | R195 R197 R205 R209 R217 R219 R222 R223 R228 R232 R241 R243 R247 R251 R255 R263 R265 R268 R273 R274 R280 R286 R289 R293 R297 R300 R303 R311 R315 R319 R320 R326 R332 R335 R339 R343 |
| 3 | B55.01103.M002 | 64.13735.6DL | CHIP RES 137K F 1/16W 0402 | R2_SA;HF_SA;G_SA; | TAI;RALEC;CYNTEC;YAGEO;WALSIN | RM04FTN1373;RTT021373FTH;RR-0510S-1373-FN;RC0402FR-07137KL;WR04X1373FTL | Multiple |  | Purchase | SMT | 2 | PCS | R1057 R1091 |
| 3 | B55.01103.M002 | 64.14335.L0L | CHIP RES 143K F 1/16W 0402 | R2_SA;HF_SA;G_SA; | TAI;RALEC;CYNTEC | RM04FTN1433;RTT021433FTH;RR0510S-1433-FN | Multiple |  | Purchase | SMT | 4 | PCS | R1218 R1237 R1255 R1275 |
| 3 | B55.01103.M002 | 64.15025.6DL | CHIP RES 15K F 1/16W 0402 | R2_SA;HF_SA;G_SA; | TA-I;RALEC;CYNTEC;YAGEO | RM04FTN1502;RTT021502FTH;RR0510S-153-FN;RC0402FR-0715KL | Multiple |  | Purchase | SMT | 5 | PCS | R1213 R1233 R1252 R1271 R1291 |
| 3 | B55.01103.M002 | 64.16225.6DL | CHIP RES 16.2K F 1/16W 0402 | R2_SA;HF_SA;G_SA; | TAI;YAGEO;CYNTEC;RALEC | RM04FTN1622;RC0402FR-0716K2L;RR0510S-1622-F;RTT021622FTH | Multiple |  | Purchase | SMT | 4 | PCS | R165 R182 R186 R25 |
| 3 | B55.01103.M002 | 64.20015.6DL | CHIP RES 2K F 1/16W 0402 | R2_SA;HF_SA;G_SA; | TA-I;RALEC;CYNTEC;YAGEO;WALSIN | RM04FTN2001 ; RTT022001FTH ; RR0510S-202-FN ; RC0402FR-072KL;WR04X2001FTL | Multiple |  | Purchase | SMT | 1 | PCS | R1289 |
| 3 | B55.01103.M002 | 64.20035.6DL | CHIP RES 200K F 1/16W 0402 | R2_SA;HF_SA;G_SA; | TA-I;RALEC;CYNTEC;YAGEO;WALSIN | RM04FTN2003 ; RTT022003FTH ; RR0510S-204-FN ; RC0402FR-07200KL;WR04X2003FTL | Multiple |  | Purchase | SMT | 40 | PCS | R1212 R1232 R1251 R1270 R169 R192 R215 R238 R261 R284 R307 R330 R353 R376 R399 R422 R445 R468 R491 R514 R537 R560 R583 R606 R629 R652 R675 R698 R721 R744 R767 R790 R813 R836 R859 R882 R905 R928 R951 R974 |
| 3 | B55.01103.M002 | 64.21025.6DL | CHIP RES 21K F 1/16W 0402 | R2_SA;HF_SA;G_SA; | TA-I ; RALEC ; CYNTEC ; YAGEO;WALSIN | RM04FTN2102 ; RTT022102FTH ; RR0510S-2102-FN ; RC0402FR-0721KL;WR04X2102FTL | Multiple |  | Purchase | SMT | 1 | PCS | R1161 |
| 3 | B55.01103.M002 | 64.22005.55L | CHIP RES 220 F 1/10W 0603 | R2_SA;HF_SA;G_SA; | TAI;RALEC;YAGEO;WALSIN | RM06FTN2200;RTT032200FTP;RC0603FR-07220RL;WR06X2200FTL | Multiple |  | Purchase | SMT | 36 | PCS | R155 R180 R203 R226 R249 R272 R295 R318 R341 R364 R387 R410 R433 R456 R479 R502 R525 R548 R571 R594 R617 R640 R663 R686 R709 R732 R755 R778 R801 R824 R847 R870 R893 R916 R939 R962 |
| 3 | B55.01103.M002 | 64.22015.6DL | CHIP RES 2.2K F 1/16W 0402 | R2_SA;HF_SA;G_SA; | TA-I;RALEC;CYNTEC;YAGEO | RM04FTN2201;RTT022201FTH;RR0510S-222-FN;RC0402FR-072K2L | Multiple |  | Purchase | SMT | 8 | PCS | R1297 R1298 R1299 R1300 R601 R603 R608 R609 |
| 3 | B55.01103.M002 | 64.22R65.6DL | CHIP RES 22.6 F 1/16W 0402 | R2_SA;HF_SA;G_SA; | TA-I;RALEC;CYNTEC;YAGEO;WALSIN | RM04FTN22R6 ; RTT0222R6FTH ; RR0510S-22R6-FN ; RC0402FR-0722R6L;WR04X22R6FTL | Multiple |  | Purchase | SMT | 2 | PCS | R1061 R1095 |
| 3 | B55.01103.M002 | 64.27015.6DL | CHIP RES 2.7K F 1/16W 0402 | R2_SA;HF_SA;G_SA; | TAI;RALEC;CYNTEC;YAGEO | RM04FTN2701;RTT022701FTH;RR0510S-2701-FN;RC0402FR-072K7L | Multiple |  | Purchase | SMT | 4 | PCS | R1211 R1230 R1249 R1268 |
| 3 | B55.01103.M002 | 64.2R005.81L | CHIP RES 2 F 1/2W 1206 | R2_SA;HF_SA;G_SA; | TAI;YAGEO;CYNTEC | RMH12FT2R00;RC1206FR-7W2RL;RL1632H-2R0-FN | Multiple |  | Purchase | SMT | 72 | PCS | R152 R154 R175 R179 R198 R202 R221 R225 R244 R248 R267 R271 R290 R294 R313 R317 R336 R340 R359 R363 R382 R384 R405 R407 R428 R430 R451 R453 R474 R476 R497 R499 R520 R522 R543 R545 R566 R568 R589 R591 R612 R614 R635 R637 R658 R660 R681 R683 R704 R706 R727 R729 R750 R752 R773 R775 R796 R798 R819 R821 R842 R844 R865 R867 R888 R890 R911 R913 R934 R936 R957 R959 |
| 3 | B55.01103.M002 | 64.2R205.55L | CHIP RES 2.2 F 1/10W 0603 | R2_SA;HF_SA;G_SA; | TAI;YAGEO;RALEC;WALSIN | RM06FTN2R20;RC0603FR-072R2L;RTT032R20FTP;WR06W2R20FTL | Multiple |  | Purchase | SMT | 5 | PCS | R1206 R1226 R1245 R1264 R1281 |
| 3 | B55.01103.M002 | 64.30035.6DL | CHIP RES 300K F 1/16W 0402 | R2_SA;HF_SA;G_SA; | TAI;RALEC;CYNTEC;YAGEO;WALSIN | RM04FTN3003;RTT023003FTH;RR0510S-304-FN;RC0402FR-07300KL;WR04X3003FTL | Multiple |  | Purchase | SMT | 36 | PCS | R167 R191 R214 R237 R260 R283 R306 R329 R352 R375 R398 R421 R442 R467 R490 R513 R536 R559 R582 R605 R628 R651 R672 R697 R720 R743 R766 R789 R812 R835 R857 R880 R903 R925 R950 R973 |
| 3 | B55.01103.M002 | 64.30935.6DL | CHIP RES 309K F 1/16W 0402 | R2_SA;HF_SA;G_SA; | TA-I;RALEC;CYNTEC;YAGEO | RM04FTN3093;RTT023093FTH;RR0510S-3093-FN;RC0402FR-07309KL | Multiple |  | Purchase | SMT | 4 | PCS | R1219 R1238 R1257 R1276 |
| 3 | B55.01103.M002 | 64.33015.55L | CHIP RES 3.3K F 1/10W 0603(ROH | R2_SA;HF_SA;G_SA; | TAI;RALEC;YAGEO | RM06FTN3301;RTT033301FTP;RC0603FR-073K3L | Multiple |  | Purchase | SMT | 3 | PCS | R1293 R1294 R1295 |
| 3 | B55.01103.M002 | 64.38315.6DL | CHIP RES 3.83K F 1/16W 0402 | R2_SA;HF_SA;G_SA; | TA-I;RALEC;CYNTEC;YAGEO | RM04FTN3831;RTT023831FTH;RR0510S-3831-FN;RC0402FR-073K83L | Multiple |  | Purchase | SMT | 4 | PCS | R1055 R1089 R1131 R1159 |
| 3 | B55.01103.M002 | 64.39215.6DL | CHIP RES 3.92K F 1/16W 0402 | R2_SA;HF_SA;G_SA; | RALEC ; CYNTEC ; TA-I ; YAGEO | RTT023921FTH ; RR0510S-3921-FN ; RM04FTN3921 ; RC0402FR-073K92L | Multiple |  | Purchase | SMT | 3 | PCS | R1065 R1099 R1170 |
| 3 | B55.01103.M002 | 64.47015.6DL | CHIP RES 4.7K F 1/16W 0402 | R2_SA;HF_SA;G_SA; | TA-I;RALEC;CYNTEC;YAGEO;WALSIN | RM04FTN4701;RTT024701FTH;RR0510S-472-FN;RC0402FR-074K7L;WR04X4701FTL | Multiple |  | Purchase | SMT | 52 | PCS | R101 R102 R104 R109 R112 R113 R116 R117 R119 R121 R122 R126 R134 R136 R138 R140 R148 R158 R171 R173 R176 R2 R28 R32 R33 R34 R36 R45 R48 R50 R51 R53 R54 R6 R62 R64 R68 R69 R70 R72 R76 R77 R78 R8 R80 R81 R88 R89 R94 R97 R98 R99 |
| 3 | B55.01103.M002 | 64.49925.6DL | CHIP RES 49.9K F 1/16W 0402 | R2_SA;HF_SA;G_SA; | TA-I ; RALEC ; CYNTEC ; YAGEO ; WALSIN | RM04FTN4992 ; RTT024992FTH ; RR0510S-4992-FN ; RC0402FR-0749K9L ; WR04X4992FTL | Multiple |  | Purchase | SMT | 6 | PCS | R1063 R1064 R1097 R1098 R1167 R1168 |
| 3 | B55.01103.M002 | 64.62025.6DL | CHIP RES 62K F 1/16W 0402(ROHS | R2_SA;HF_SA;G_SA; | YAGEO;TAI;RALEC;CYNTEC | RC0402FR-0762KL;RM04FTN6202;RTT026202FTH;RR0510S-623-FN | Multiple |  | Purchase | SMT | 2 | PCS | R1059 R1093 |
| 3 | B55.01103.M002 | 64.73215.6DL | CHIP RES 7.32K F 1/16W 0402 | R2_SA;HF_SA;G_SA; | TA-I;RALEC;CYNTEC;YAGEO;WALSIN | RM04FTN7321;RTT027321FTH;RR0510S-7321-FN;RC0402FR-077K32L;WR04X7321FTL | Multiple |  | Purchase | SMT | 1 | PCS | R27 |
| 3 | B55.01103.M002 | 64.75025.6DL | CHIP RES 75K F 1/16W 0402 | R2_SA;HF_SA;G_SA; | TA-I;RALEC;CYNTEC;YAGEO;WALSIN | RM04FTN7502;RTT027502FTH;RR0510S-753-FN;RC0402FR-0775KL;WR04X7502FTL | Multiple |  | Purchase | SMT | 1 | PCS | R1163 |
| 3 | B55.01103.M002 | 64.91R05.55L | CHIP RES 91 F 1/10W 0603 | R2_SA;HF_SA;G_SA; | TA-I ; RALEC ; YAGEO | RM06FTN91R0 ; RTT0391R0FTP ; RC0603FR-0791RL | Multiple |  | Purchase | SMT | 36 | PCS | R196 R199 R208 R210 R218 R220 R227 R230 R233 R240 R242 R246 R250 R254 R257 R264 R266 R269 R277 R278 R287 R288 R292 R296 R301 R309 R310 R312 R316 R323 R324 R333 R334 R338 R342 R346 |
| 3 | B55.01103.M002 | 64.R0015.L1L | CHIP RES 0.001 F 1W 0612 | R2_SA;HF_SA; | VISHAY | WSK06121L000FEA | Multiple |  | Purchase | SMT | 2 | PCS | R1062 R1096 |
| A | B55.01103.M002 | 64.R0015.70L | CHIP RES 0.001 F 1W 0612 | R2_SA;HF_SA; | CYNTEC | RL1632L4-R001-FNH |  |  | Purchase |  |  |  |  |
| 3 | B55.01103.M002 | 68.00084.831 | CHIP BEAD BLM21PG220SN1D (LF) | R2_SA;HF_SA; | MURATA | BLM21PG220SN1D | Multiple |  | Purchase | SMT | 4 | PCS | L1 L3 L5 L7 |
| A | B55.01103.M002 | 68.00216.081 | CHIP BEAD HCB2012KF-220T60 | R2_SA;HF_SA; | TAITECH | HCB2012KF-220T60 |  |  | Purchase |  |  |  |  |
| 3 | B55.01103.M002 | 68.1R010.20K | CHIP CHOKE 1.0UH PCMB103T-1R0MS | R2_SA;HF_SA;G_SA; | CYNTEC | PCMB103T-1R0MS | Multiple |  | Purchase | SMT | 4 | PCS | L2 L4 L6 L8 |
| A | B55.01103.M002 | 68.1R01E.10H | CHIP IND 1.0UH M MMD-10CZ-1R0M-X2W | R2_SA;HF_SA; | MAGLAYER | MMD-10CZ-1R0M-X2W |  |  | Purchase |  |  |  |  |
| 3 | B55.01103.M002 | 68.4R71A.20H | CHIP CHOKE 4.7UH PCMB063T-4R7MS | R2_SA;HF_SA; | CYNTEC | PCMB063T-4R7MS | Multiple |  | Purchase | SMT | 1 | PCS | L9 |
| A | B55.01103.M002 | 68.4R71C.10U | CHIP IND 4.7UH SPM6530T-4R7M | R2_SA;HF_SA; | TDK | SPM6530T-4R7M |  |  | Purchase |  |  |  |  |
| 3 | B55.01103.M002 | 71.09557.D0W | IC I2C/SMBUS PCA9557PWR TSSOP 16P | R2_SA;HF_SA; | TI | PCA9557PWR | Multiple |  | Purchase | SMT | 1 | PCS | U9 |
| A | B55.01103.M002 | 071.09557.000W | IC IC2/SMBUS PCA9557PW,118 TSSOP 16P | R2_SA;HF_SA; | NXP | PCA9557PW,118 |  |  | Purchase |  |  |  |  |
| 3 | B55.01103.M002 | 71.P9511.00W | IC BUF PCA9511ADP-T TSSOP 8P | R2_SA;HF_SA; | NXP | PCA9511ADP-T | Single |  | Purchase | SMT | 2 | PCS | U15 U16 |
| 3 | B55.01103.M002 | 72.24C64.K01 | IC EEPROM M24C64-RMN6TP SOIC 8P | R2_SA;HF_SA; | STMICROELECTRONICS INC | M24C64-RMN6TP | Multiple |  | Purchase | SMT | 1 | PCS | U1 |
| A | B55.01103.M002 | 072.02464.0A01 | IC EEPROM FM24C64D-SO-T-G SOP 8P | R2_SA;HF_SA; | FUDAN | FM24C64D-SO-T-G |  |  | Purchase |  |  |  |  |
| 3 | B55.01103.M002 | 73.01G08.L03 | IC CMOS SN74LVC1G08DCKR SC-70 | R2_SA;HF_SA;G_SA; | TI | SN74LVC1G08DCKR | Multiple |  | Purchase | SMT | 5 | PCS | U31 U32 U36 U47 U48 |
| A | B55.01103.M002 | 073.7SZ08.000G | IC CMOS TC7SZ08FU,LJ(CT SSOP5-P-0.65A | R2_SA;HF_SA; | TOSHIBA | TC7SZ08FU,LJ(CT |  |  | Purchase |  |  |  |  |
| A | B55.01103.M002 | 73.01G08.DHG | IC CMOS SN74LVC1G08DCKRG4 DCK | R2_SA;HF_SA;G_SA; | TI | SN74LVC1G08DCKRG4 |  |  | Purchase |  |  |  |  |
| 3 | B55.01103.M002 | 73.01G32.A0H | IC CMOS SN74LVC1G32DCKR SC70-5 | R2_SA;HF_SA; | TI | SN74LVC1G32DCKR | Multiple |  | Purchase | SMT | 2 | PCS | U28 U29 |
| A | B55.01103.M002 | 73.01G32.AHH | IC CMOS 74LVC1G32GW,125 SC70-5 | R2_SA;HF_SA;G_SA; | NXP | 74LVC1G32GW,125 |  |  | Purchase |  |  |  |  |
| A | B55.01103.M002 | 73.7SZ32.AAH | IC CMOS NC7SZ32P5X_NL SC70-5 | R2_SA;HF_SA;G_SA; | FAIRCHILD | NC7SZ32P5X_NL |  |  | Purchase |  |  |  |  |
| 3 | B55.01103.M002 | 73.1G126.DHG | IC CMOS SN74LVC1G126DCKR SC70 | R2_SA;HF_SA; | TI | SN74LVC1G126DCKR | Multiple |  | Purchase | SMT | 2 | PCS | U30 U42 |
| A | B55.01103.M002 | 073.7S126.000G | IC CMOS TC7SZ126FU,LJ(CT SSOP5-P-0.65A | R2_SA;HF_SA; | TOSHIBA | TC7SZ126FU,LJ(CT |  |  | Purchase |  |  |  |  |
| A | B55.01103.M002 | 73.7S126.AAH | IC CMOS NC7SZ126P5X SC70-5 | R2_SA;HF_SA; | FAIRCHILD | NC7SZ126P5X |  |  | Purchase |  |  |  |  |
| 3 | B55.01103.M002 | 74.02065.07F | IC PWR SW TPS2065DBVT SOT-23 5P | R2_SA;HF_SA; | TI | TPS2065DBVT | Single |  | Purchase | SMT | 2 | PCS | U34 U35 |
| 3 | B55.01103.M002 | 74.53312.073 | IC PWM CTRL TPS53312RGTR QFN 16P | R2_SA;HF_SA; | TI | TPS53312RGTR | Single |  | Purchase | SMT | 1 | PCS | U33 |
| 3 | B55.01103.M002 | 74.53319.073 | IC PWR CTRL TPS53319DQPR QFN 22P | R2_SA;HF_SA; | TI | TPS53319DQPR | Single |  | Purchase | SMT | 4 | PCS | U20 U21 U22 U27 |
| 3 | B55.01103.M002 | 77.21071.02L | CHIP CAP POS 100U 16V M7343 ESR | R2_SA;HF_SA; | PANASONIC | 16TQC100MYF | Single |  | Purchase | SMT | 4 | PCS | TC1 TC21 TC3 TC4 |
| 3 | B55.01103.M002 | 77.22271.L03 | CHIP CAP POS 220U 10V M7343 | R2_SA;HF_SA; | PANASONIC | 10TPE220ML | Single |  | Purchase | SMT | 8 | PCS | TC10 TC11 TC12 TC5 TC6 TC7 TC8 TC9 |
| 3 | B55.01103.M002 | 78.10134.1FL | CHIP CAP C 100P 50V J0402 NPO | R2_SA;HF_SA;G_SA; | AVX;DARFON;MURATA;PHYCOMP;SAMSUNG;TAIYO;WALSIN;YAGEO | CM05CG101J50AH;C1005NP0101JGT;GRM1555C1H101JA01D;223886915101;CL05C101JB5NNNC;UMK105CH101JV-F;0402N101J500CT;CC0402JRNPO9BN101 | Multiple |  | Purchase | SMT | 1 | PCS | C673 |
| 3 | B55.01103.M002 | 78.10224.2FL | CHIP CAP C 1000P 50V K0402 X7R | R2_SA;R_SA;HF_SA;G_SA; | AVX;DARFON;MURATA;PHYCOMP;SAMSUNG;TAIYO;MURATA;AVX;YAGEO | CM05X7R102K50AH;C1005X7R102KGT;GRM155R71H102KA01D;223858715623;CL05B102KB5NNNC;UMK105B7102KV-F;WBM155R71H102KA01D;04025C102KAT2A;CC0402KRX7R9BB102 | Multiple |  | Purchase | SMT | 4 | PCS | C541 C555 C583 C679 |
| 3 | B55.01103.M002 | 78.10322.2FL | CHIP CAP C 0.01U 25V K0402 X7R | R2_SA;HF_SA;G_SA; | AVX;DARFON;MURATA;PHYCOMP;SAMSUNG;TAIYO;TDK;MURATA;YAGEO | 04023C103KAT2A;C1005X7R103KFT;GRM155R71E103KA01D;223891715636;CL05B103KA5NNNC;TMK105BJ103KV-F;C1005X7R1E103KT000F;WBM155R71E103KA01D;CC0402KRX7R8BB103 | Multiple |  | Purchase | SMT | 2 | PCS | C542 C556 |
| 3 | B55.01103.M002 | 78.10324.2FL | CHIP CAP C 0.01U 50V K0402 X7R | R2_SA;HF_SA;G_SA; | MURATA;PHYCOMP;DARFON;SAMSUNG;WALSIN;MURATA;YAGEO | GRM155R71H103KA88D;223858715636;C1005X7R103KGT;CL05B103KB5NNNC;0402B103K500CT;WBM155R71H103KA01D;CC0402KRX7R9BB103 | Multiple |  | Purchase | SMT | 36 | PCS | C111 C124 C136 C149 C163 C176 C189 C198 C215 C226 C237 C253 C267 C279 C293 C303 C315 C331 C345 C358 C371 C384 C396 C410 C423 C432 C449 C458 C474 C487 C497 C513 C55 C70 C84 C98 |
| 3 | B55.01103.M002 | 78.10421.2FL | CHIP CAP C 0.1U 16V K0402 X7R | R2_SA;HF_SA;G_SA; | DARFON;MURATA;PHYCOMP;SAMSUNG;TAIYO;WALSIN;YAGEO | C1005X7R104KET;GRM155R71C104KA88D;223878715649;CL05B104KO5NNNC;EMK105B7104KV-F;0402B104K160CT;CC0402KRX7R7BB104 | Multiple |  | Purchase | SMT | 51 | PCS | C1 C10 C102 C12 C14 C15 C159 C16 C18 C19 C2 C22 C24 C26 C27 C28 C3 C30 C33 C36 C38 C43 C47 C48 C49 C5 C50 C536 C544 C558 C56 C586 C6 C600 C605 C617 C622 C63 C634 C638 C651 C656 C670 C68 C680 C688 C7 C8 C81 C82 C89 |
| 3 | B55.01103.M002 | 78.10422.2BL | CHIP CAP C 0.1U 25V K0603 X7R | R2_SA;HF_SA;G_SA; | AVX;DARFON;MURATA;PHYCOMP;SAMSUNG;TAIYO;WALSIN;YAGEO | 06033C104KAT2A;C1608X7R104KFT;GRM188R71E104KA01D;223891615649;CL10B104KA8NNNC;TMK107B7104KA-T;0603B104K250CT;CC0603KRX7R8BB104 | Multiple |  | Purchase | SMT | 1 | PCS | C678 |
| 3 | B55.01103.M002 | 78.10422.2FL | CHIP CAP C 0.1U 25V K0402 X7R | R2_SA;HF_SA;G_SA; | YAGEO;WALSIN;MURATA;SAMSUNG;TAIYO;DARFON | CC0402KRX7R8BB104;0402B104K250CT;GRM155R71E104KE14D;CL05B104KA5NNNC;TMK105B7104KV-FR;C1005X7R104KFT | Multiple |  | Purchase | SMT | 12 | PCS | C547 C548 C550 C551 C561 C562 C564 C565 C589 C590 C592 C593 |
| 3 | B55.01103.M002 | 78.10424.2BL | CHIP CAP C 0.1U 50V K0603 X7R | R2_SA;HF_SA;G_SA; | MURATA;AVX;PHYCOMP;SAMSUNG;DARFON;WALSIN;YAGEO | GRM188R71H104KA93D;06035C104KAT2A;223858615649;CL10B104KB8NNNC;C1608X7R104KGT;0603B104K500CT;CC0603KRX7R9BB104 | Multiple |  | Purchase | SMT | 4 | PCS | C608 C624 C642 C658 |
| 3 | B55.01103.M002 | 78.10521.2BL | CHIP CAP C 1U 16V K0603 X7R | R2_SA;HF_SA;G_SA; | KEMET;MURATA;TAIYO;TDK;YAGEO;WALSIN;SAMSUNG;DARFON | C0603C105K4RAC;GRM188R71C105KA12D;EMK107B7105KA-T;C1608X7R1C105KT;CC0603KRX7R7BB105;0603B105K160CT;CL10B105KO8NNNC;C1608X7R105KET | Multiple |  | Purchase | SMT | 71 | PCS | C105 C11 C118 C13 C131 C144 C157 C17 C170 C183 C196 C20 C209 C21 C222 C23 C235 C248 C25 C261 C274 C287 C29 C300 C313 C326 C339 C34 C35 C352 C365 C37 C378 C391 C4 C404 C417 C42 C430 C443 C456 C46 C469 C482 C495 C508 C53 C535 C549 C552 C553 C563 C566 C567 C57 C591 C594 C595 C606 C625 C641 C659 C66 C669 C676 C69 C79 C9 C92 C94 C95 |
| 3 | B55.01103.M002 | 78.10522.2BL | CHIP CAP C 1U 25V K0603 X7R | R2_SA;HF_SA;G_SA; | MURATA;TAIYO;WALSIN;SAMSUNG;DARFON;YAGEO | GRM188R71E105KA12D;TMK107B7105KA-T;0603B105K250CT;CL10B105KA8NNNC;C1608X7R105KFT;CC0603KRX7R8BB105 | Multiple |  | Purchase | SMT | 40 | PCS | C112 C125 C138 C151 C164 C177 C190 C203 C216 C229 C242 C255 C268 C281 C294 C307 C320 C333 C346 C359 C372 C385 C398 C411 C424 C437 C450 C463 C476 C489 C502 C515 C543 C557 C585 C60 C674 C73 C86 C99 |
| 3 | B55.01103.M002 | 78.10620.21L | CHIP CAP C 10U 6.3V K0805 X7R | R2_SA;HF_SA;G_SA; | MURATA;TAIYO;DARFON;KYOCERA | GRM21BR70J106KE76L;JMK212B7106KG-T;C2012X7R106KC;CM21X7R106K06AT | Multiple |  | Purchase | SMT | 6 | PCS | C681 C682 C683 C684 C685 C686 |
| 3 | B55.01103.M002 | 78.10621.22L | CHIP CAP C 10U 16V K1206 X7R | R2_SA;HF_SA;G_SA; | MURATA;TDK;AVX;DARFON;SAMSUNG;TAIYO;WALSIN | GRM31CR71C106KA12L;C3216X7R1C106KT;CM316X7R106K16AT;C3216X7R106KEP;CL31B106KOHNNNE;EMK316B7106KL-T;1206B106K160CT | Multiple |  | Purchase | SMT | 36 | PCS | C106 C119 C132 C145 C158 C171 C184 C197 C210 C223 C236 C249 C262 C275 C288 C301 C314 C327 C340 C353 C366 C379 C392 C405 C418 C431 C444 C457 C470 C483 C496 C509 C54 C67 C80 C93 |
| 3 | B55.01103.M002 | 78.15322.2FL | CHIP CAP C 0.015U 25V K0402 X7R | R2_SA;HF_SA;G_SA; | MURATA;TDK;WALSIN;DARFON;PHYCOMP | GRM155R71E153KA61D;C1005X7R1E153KT000F;0402B153K250CT;C1005X7R153KFT;223891715638 | Multiple |  | Purchase | SMT | 3 | PCS | C545 C559 C587 |
| 3 | B55.01103.M002 | 78.22421.2FL | CHIP CAP C 0.22U 16V K0402 X7R | R2_SA;HF_SA;G_SA; | MURATA;SAMSUNG;DARFON;TAIYO;WALSIN;YAGEO | GRM155R71C224KA12D;CL05B224KO5NNNC;C1005X7R224KET;EMK105B7224KV-FR;0402B224K160CT;CC0402KRX7R7BB224 | Multiple |  | Purchase | SMT | 1 | PCS | C584 |
| 3 | B55.01103.M002 | 78.22522.21L | CHIP CAP C 2.2U 25V K0805 X7R | R2_SA;HF_SA;G_SA; | WALSIN ; SAMSUNG ; PHYCOMP | 0805B225K250CT ; CL21B225KAFNNNE ; 222291015667 | Multiple |  | Purchase | SMT | 6 | PCS | C120 C133 C31 C39 C523 C531 |
| 3 | B55.01103.M002 | 78.33224.2FL | CHIP CAP C 3300P 50V K0402 X7R | R2_SA;HF_SA;G_SA; | MURATA;AVX;TAIYO;PHYCOMP;DARFON;WALSIN;YAGEO | GRM155R71H332KA01D;04025C332KAT2A;UMK105B7332KV-F;223858715629;C1005X7R332KGT;0402B332K500CT;CC0402KRX7R9BB332 | Multiple |  | Purchase | SMT | 1 | PCS | C675 |
| 3 | B55.01103.M002 | 78.33322.2FL | CHIP CAP C 0.033U 25V K0402 X7 | R2_SA;HF_SA;G_SA; | MURATA;TDK;KEMET;WALSIN;PHYCOMP;YAGEO | GRM155R71E333KA88D;C1005X7R1E333KT000F;C0402C333K3RACTU;0402B333K250CT;223891715643;CC0402KRX7R8BB333 | Multiple |  | Purchase | SMT | 72 | PCS | C100 C101 C113 C114 C126 C127 C139 C140 C152 C153 C165 C166 C178 C179 C191 C192 C204 C205 C217 C218 C230 C231 C243 C244 C256 C257 C269 C270 C282 C283 C295 C296 C308 C309 C321 C322 C334 C335 C347 C348 C360 C361 C373 C374 C386 C387 C399 C400 C412 C413 C425 C426 C438 C439 C451 C452 C464 C465 C477 C478 C490 C491 C503 C504 C516 C517 C61 C62 C74 C75 C87 C88 |
| 3 | B55.01103.M002 | 78.33324.2BL | CHIP CAP 0.033U 50V K0603 X7R | R2_SA;HF_SA;G_SA; | MURATA;AVX;PHYCOMP;DARFON;YAGEO | GRM188R71H333KA61D;06035C333KAT2A;223858615643;C1608X7R333KGT;CC0603KRX7R9BB333 | Multiple |  | Purchase | SMT | 3 | PCS | C554 C568 C596 |
| 3 | B55.01103.M002 | 78.47124.2FL | CHIP CAP C 470P  50V K0402 X7R | R2_SA;HF_SA;G_SA; | AVX;DARFON;MURATA;PHYCOMP;TAIYO;SAMSUNG;WALSIN;YAGEO | 04025C471KAT2A;C1005X7R471KGT;GRM155R71H471KA01D;223858715618;UMK105B7471KV-F;CL05B471KB5NNNC;0402B471K500CT;CC0402KRX7R9BB471 | Multiple |  | Purchase | SMT | 4 | PCS | C609 C626 C643 C660 |
| 3 | B55.01103.M002 | 78.47522.51L | CHIP CAP C 4.7U 25V K0805 X5R | R2_SA;HF_SA;G_SA; | MURATA;AVX;TAIYO;SAMSUNG;PHYCOMP;YAGEO | GRM21BR61E475KA12L;CM21X5R475K25AT;TMK212BJ475KG-T;CL21A475KAQNNNG;222291013672;CC0805KKX5R8BB475 | Multiple |  | Purchase | SMT | 4 | PCS | C604 C621 C639 C655 |
| 3 | B55.01103.M002 | 78.47611.53L | CHIP CAP C 47U 16V M1210 X5R | R2_SA;HF_SA;G_SA; | MURATA;TAIYO;TAIYO;DARFON | GRM32ER61C476ME15L;EMK325BJ476MM-T;EMK325BJ476MM-P;C3225X5R476MEP | Multiple |  | Purchase | SMT | 2 | PCS | C45 C76 |
| A | B55.01103.M002 | 078.47611.0831 | CHIP CAP C 47UF 16V M1210 X6S | R2_SA;HF_SA; | MURATA;TAIYO;DARFON | GRM32EC81C476ME15L;EMK325AC6476MM-P;C3225X6S476MEP |  |  | Purchase |  |  |  |  |
| 3 | B55.01103.M002 | 83.3R903.B3F | DIODE ZEN MMPZ5228BPT SOD-323 | R2_SA;G_SA; | CHENMKO | MMPZ5228BPT | Multiple |  | Purchase | SMT | 3 | PCS | D41 D42 D43 |
| A | B55.01103.M002 | 083.3Z3V9.003F | DIODE ZEN LM3Z3V9T1G SOD-323 | R2_SA;HF_SA; | LRC | LM3Z3V9T1G |  |  | Purchase |  |  |  |  |
| A | B55.01103.M002 | 83.3R903.E3F | DIODE ZEN MM3Z3V9T1G 3.9V SOD-323 | R2_SA;HF_SA; | ON | MM3Z3V9T1G |  |  | Purchase |  |  |  |  |
| 3 | B55.01103.M002 | 83.R5003.H8H | DIODE S.B RB551V30 0.5A 30V SOD-323 | R2_SA;HF_SA;G_SA; | PANJIT | RB551V30 | Multiple |  | Purchase | SMT | 36 | PCS | D1 D10 D11 D12 D13 D14 D15 D16 D17 D18 D19 D2 D20 D21 D22 D23 D24 D25 D26 D27 D28 D29 D3 D30 D31 D32 D33 D34 D35 D36 D4 D5 D6 D7 D8 D9 |
| A | B55.01103.M002 | 83.R5003.T8F | DIODE S.B LRB551V-30T1G SOD-323 | R2_SA;HF_SA; | LRC | LRB551V-30T1G |  |  | Purchase |  |  |  |  |
| 3 | B55.01103.M002 | 83.SMC14.AAG | DIODE TVS SMCJ14A-13-F DO-214AB | R2_SA;HF_SA; | DIODES | SMCJ14A-13-F | Single |  | Purchase | SMT | 3 | PCS | D37 D38 D40 |
| 3 | B55.01103.M002 | 84.03904.T11 | XTOR MMBT3904 NPN SOT-23 | R2_SA;HF_SA;G_SA; | PANJIT | MMBT3904 | Multiple |  | Purchase | SMT | 3 | PCS | Q219 Q221 Q225 |
| A | B55.01103.M002 | 84.03904.L06 | XTOR PMBS3904,215 NPN SOT23 (GP) | R2_SA;HF_SA;G_SA; | NEXPERIA | PMBS3904,215 |  |  | Purchase |  |  |  |  |
| A | B55.01103.M002 | 84.T3904.H11 | XTOR LMBT3904LT1G NPN SOT-23 | R2_SA;HF_SA;G_SA; | LRC | LMBT3904LT1G |  |  | Purchase |  |  |  |  |
| 3 | B55.01103.M002 | 84.04407.G37 | FET MOS AO4407AL PC SOIC8(HF) | R2_SA;HF_SA; | AOS | AO4407AL | Multiple |  | Purchase | SMT | 36 | PCS | Q104 Q110 Q116 Q122 Q128 Q134 Q14 Q140 Q146 Q152 Q158 Q164 Q170 Q176 Q182 Q188 Q194 Q20 Q200 Q206 Q212 Q218 Q26 Q32 Q38 Q44 Q50 Q56 Q62 Q68 Q74 Q8 Q80 Q86 Q92 Q98 |
| A | B55.01103.M002 | 84.04825.A37 | FET MOS SI4825DDY PC SO 8P | R2_SA;HF_SA; | VISHAY | SI4825DDY |  |  | Purchase |  |  |  |  |
| 3 | B55.01103.M002 | 84.08878.A37 | FET MOS FDS8878_G NC SO-8(HF) | R2_SA;HF_SA; | FAIRCHILD | FDS8878_G | Multiple |  | Purchase | SMT | 36 | PCS | Q101 Q108 Q113 Q119 Q12 Q125 Q132 Q137 Q144 Q149 Q155 Q161 Q168 Q174 Q18 Q180 Q185 Q191 Q197 Q203 Q209 Q215 Q24 Q30 Q36 Q42 Q48 Q5 Q54 Q60 Q66 Q72 Q77 Q83 Q89 Q96 |
| A | B55.01103.M002 | 84.04172.037 | FET MOS SI4172DY-T1-GE3 NC SO8 | R2_SA;HF_SA; | VISHAY | SI4172DY-T1-GE3 |  |  | Purchase |  |  |  |  |
| 3 | B55.01103.M002 | 84.2N702.031 | FET MOS 2N7002K-7 NC SOT-23 2KV 300MA | R2_SA;HF_SA; | DIODES | 2N7002K-7 | Single |  | Purchase | SMT | 2 | PCS | Q21 Q22 |
| 3 | B55.01103.M002 | 84.2N702.A3F | FET MOS 2N7002KDW NC SOT-363 ESD 2KV | R2_SA;HF_SA;G_SA; | PANJIT | 2N7002KDW | Multiple |  | Purchase | SMT | 40 | PCS | Q1 Q103 Q109 Q115 Q121 Q127 Q13 Q133 Q139 Q145 Q151 Q157 Q163 Q169 Q175 Q181 Q187 Q19 Q193 Q199 Q2 Q205 Q211 Q217 Q25 Q3 Q31 Q37 Q4 Q43 Q49 Q55 Q61 Q67 Q7 Q73 Q79 Q85 Q91 Q97 |
| A | B55.01103.M002 | 075.063D1.007C | IC FETMOS DMN63D1LDW-7 NC SOT-363 ESD 2K | R2_SA;HF_SA; | DIODES | DMN63D1LDW-7 |  |  | Purchase |  |  |  |  |
| 3 | B55.01103.M002 | 84.2N702.J31 | FET MOS 2N7002K NC SOT-23 ESD 2KV 300MA | R2_SA;HF_SA;G_SA; | PANJIT | 2N7002K | Multiple |  | Purchase | SMT | 36 | PCS | Q223 Q224 Q229 Q230 Q231 Q232 Q233 Q234 Q235 Q236 Q237 Q238 Q239 Q240 Q241 Q242 Q243 Q244 Q245 Q246 Q247 Q248 Q249 Q250 Q251 Q252 Q253 Q254 Q255 Q256 Q257 Q258 Q259 Q262 Q298 Q300 |
| A | B55.01103.M002 | 084.27002.0L31 | FET MOS T2N7002BK NC SOT-23 | R2_SA;HF_SA; | TOSHIBA | T2N7002BK |  |  | Purchase |  |  |  |  |
| 3 | B55.01103.M002 | 84.M3904.01K | XTOR MMBT3904TT1G NPN SOT-416 | R2_SA;HF_SA; | ON | MMBT3904TT1G | Multiple |  | Purchase | SMT | 3 | PCS | Q10 Q6 Q9 |
| A | B55.01103.M002 | 84.04617.A1H | XTOR 2SC4617GZTL NPN EMT3 | R2_SA;HF_SA; | ROHM | 2SC4617GZTL |  |  | Purchase |  |  |  |  |
| 3 | B55.01103.M002 | B48.01123.0011 | PCB 16315-1 BRYCE CANYON F.DPB CD 12L GC | R2_SA;HF_SA; | GCE | B48.01123.0011 | Multiple |  | Purchase | SMT | 1 | PCS |  |
| A | B55.01103.M002 | B48.01145.0011 | PCB 16315-1 BRYCE CANYON F.DPB CD 12L TR | R2_SA;HF_SA; | TRIPOD | B48.01145.0011 |  |  | Purchase |  |  |  |  |
